# S9S_MB_2U (Grand Teton) — schematic netlist excerpt (pin names and nets, part order shuffled) for the footprints in the layout excerpt that follows; sources: Cadence DE-HDL packaged netlist, KiCad conversion of 03242023_DA0F0TMBIJ0_F0T_Motherboard_J_brd_V01_OCP.brd

D144  Q_LED  IC  pkg SMLF  page 255 : A = LED_P12V_SCM_FAULT ; C = LED_P12V_SCM_FAULT_D2
R4189  Q_RES  1K 1% CHIP  pkg 0402LF  page 170 : A = U271_1_ADD2 ; B = GND

(kicad_pcb
	(version 20260206)
	(generator "pcbnew")
	(generator_version "10.0")
	(general
		(thickness 1.6)
		(legacy_teardrops no)
	)
	(paper "A4")
	(title_block
		(title "03242023_DA0F0TMBIJ0_F0T_Motherboard_J_brd_V01_OCP.brd")
		(comment 1 "Grand Teton / footprints 3554-3555 of 6105")
	)
	(layers
		(0 "F.Cu" signal "TOP")
		(4 "In1.Cu" signal "GND")
		(6 "In2.Cu" signal "IN1")
		(8 "In3.Cu" signal "GND1")
		(10 "In4.Cu" signal "IN2")
		(12 "In5.Cu" signal "GND2")
		(14 "In6.Cu" signal "IN3")
		(16 "In7.Cu" signal "GND3")
		(18 "In8.Cu" signal "VCC")
		(20 "In9.Cu" signal "VCC1")
		(22 "In10.Cu" signal "GND4")
		(24 "In11.Cu" signal "IN4")
		(26 "In12.Cu" signal "GND5")
		(28 "In13.Cu" signal "IN5")
		(30 "In14.Cu" signal "GND6")
		(32 "In15.Cu" signal "IN6")
		(34 "In16.Cu" signal "GND7")
		(2 "B.Cu" signal "BOTTOM")
		(9 "F.Adhes" user "F.Adhesive")
		(11 "B.Adhes" user "B.Adhesive")
		(13 "F.Paste" user "Package Geometry/Pastemask Top")
		(15 "B.Paste" user "Package Geometry/Pastemask Bottom")
		(5 "F.SilkS" user "Ref Des/Silkscreen Top")
		(7 "B.SilkS" user "Ref Des/Silkscreen Bottom")
		(1 "F.Mask" user "Board Geometry/Soldermask Top")
		(3 "B.Mask" user "Board Geometry/Soldermask Bottom")
		(17 "Dwgs.User" user "User.Drawings")
		(19 "Cmts.User" user "User.Comments")
		(21 "Eco1.User" user "User.Eco1")
		(23 "Eco2.User" user "User.Eco2")
		(25 "Edge.Cuts" user "Board Geometry/Outline")
		(27 "Margin" user)
		(31 "F.CrtYd" user "Package Geometry/Place Bound Top")
		(29 "B.CrtYd" user "Package Geometry/Place Bound Bottom")
		(35 "F.Fab" user "Ref Des/Assembly Top")
		(33 "B.Fab" user "Ref Des/Assembly Bottom")
	)
	(footprint ""
		(layer "F.Cu")
		(at 204.68336 -67.20332)
		(property "Reference" "D144"
			(at -1.397 2.82067 0)
			(unlocked yes)
			(layer "F.SilkS")
			(effects
				(font
					(size 0.7874 0.5842)
					(thickness 0.1524)
				)
				(justify left)
			)
		)
		(property "Value" ""
			(at 0 0 0)
			(layer "F.Fab")
			(effects
				(font
					(size 1.27 1.27)
				)
			)
		)
		(duplicate_pad_numbers_are_jumpers no)
		(fp_line
			(start -1.3208 -0.5588)
			(end 1.3208 -0.5588)
			(stroke
				(width 0.1524)
				(type default)
			)
			(layer "F.SilkS")
		)
		(fp_line
			(start -1.3208 0.5588)
			(end -1.3208 -0.5588)
			(stroke
				(width 0.1524)
				(type default)
			)
			(layer "F.SilkS")
		)
		(fp_line
			(start 1.3208 -0.5588)
			(end 1.3208 0.5588)
			(stroke
				(width 0.1524)
				(type default)
			)
			(layer "F.SilkS")
		)
		(fp_line
			(start 1.3208 0.5588)
			(end -1.3208 0.5588)
			(stroke
				(width 0.1524)
				(type default)
			)
			(layer "F.SilkS")
		)
		(fp_line
			(start 1.4732 -0.5588)
			(end 1.4732 0.5588)
			(stroke
				(width 0.1524)
				(type default)
			)
			(layer "F.SilkS")
		)
		(fp_line
			(start 1.6256 0.5588)
			(end 1.6256 -0.5588)
			(stroke
				(width 0.1524)
				(type default)
			)
			(layer "F.SilkS")
		)
		(fp_line
			(start 1.778 -0.5588)
			(end 1.3208 -0.5588)
			(stroke
				(width 0.1524)
				(type default)
			)
			(layer "F.SilkS")
		)
		(fp_line
			(start 1.778 -0.5588)
			(end 1.778 0.5588)
			(stroke
				(width 0.1524)
				(type default)
			)
			(layer "F.SilkS")
		)
		(fp_line
			(start 1.778 0.5588)
			(end 1.3208 0.5588)
			(stroke
				(width 0.1524)
				(type default)
			)
			(layer "F.SilkS")
		)
		(fp_line
			(start -0.899922 -0.40005)
			(end 0.899922 -0.40005)
			(stroke
				(width 0.1)
				(type default)
			)
			(layer "F.Fab")
		)
		(fp_line
			(start -0.899922 0.40005)
			(end -0.899922 -0.40005)
			(stroke
				(width 0.1)
				(type default)
			)
			(layer "F.Fab")
		)
		(fp_line
			(start 0.899922 -0.40005)
			(end 0.899922 0.40005)
			(stroke
				(width 0.1)
				(type default)
			)
			(layer "F.Fab")
		)
		(fp_line
			(start 0.899922 0.40005)
			(end -0.899922 0.40005)
			(stroke
				(width 0.1)
				(type default)
			)
			(layer "F.Fab")
		)
		(fp_text user "+"
			(at -1.61036 0.99187 0)
			(unlocked yes)
			(layer "F.SilkS")
			(effects
				(font
					(size 1.905 1.4224)
					(thickness 0.1524)
				)
				(justify left)
			)
		)
		(fp_text user "-"
			(at 0.14224 1.01727 0)
			(unlocked yes)
			(layer "F.SilkS")
			(effects
				(font
					(size 1.905 1.4224)
					(thickness 0.1524)
				)
				(justify left)
			)
		)
		(fp_text user "+"
			(at -2.6162 -0.22225 0)
			(unlocked yes)
			(layer "F.Fab")
			(effects
				(font
					(size 1.905 1.4224)
					(thickness 0.1524)
				)
				(justify left)
			)
		)
		(fp_text user "-"
			(at 1.651 -0.22225 0)
			(unlocked yes)
			(layer "F.Fab")
			(effects
				(font
					(size 1.905 1.4224)
					(thickness 0.1524)
				)
				(justify left)
			)
		)
		(pad "A" smd rect
			(at -0.750062 0)
			(size 0.8128 0.8128)
			(layers "F.Cu" "F.Mask" "F.Paste")
			(net "LED_P12V_SCM_FAULT")
		)
		(pad "C" smd rect
			(at 0.750062 0)
			(size 0.8128 0.8128)
			(layers "F.Cu" "F.Mask" "F.Paste")
			(net "LED_P12V_SCM_FAULT_D2")
		)
	)
	(footprint ""
		(layer "F.Cu")
		(at 300.733714 -14.506194)
		(property "Reference" "R4189"
			(at 0 0 0)
			(layer "F.SilkS")
			(hide yes)
			(effects
				(font
					(size 1.27 1.27)
				)
			)
		)
		(property "Value" ""
			(at 0 0 0)
			(layer "F.Fab")
			(effects
				(font
					(size 1.27 1.27)
				)
			)
		)
		(duplicate_pad_numbers_are_jumpers no)
		(fp_line
			(start -0.7874 -0.4064)
			(end 0.7874 -0.4064)
			(stroke
				(width 0.1524)
				(type default)
			)
			(layer "F.SilkS")
		)
		(fp_line
			(start -0.7874 0.4064)
			(end -0.7874 -0.4064)
			(stroke
				(width 0.1524)
				(type default)
			)
			(layer "F.SilkS")
		)
		(fp_line
			(start 0.7874 -0.4064)
			(end 0.7874 0.4064)
			(stroke
				(width 0.1524)
				(type default)
			)
			(layer "F.SilkS")
		)
		(fp_line
			(start 0.7874 0.4064)
			(end -0.7874 0.4064)
			(stroke
				(width 0.1524)
				(type default)
			)
			(layer "F.SilkS")
		)
		(fp_line
			(start -0.67945 -0.305054)
			(end -0.12065 -0.305054)
			(stroke
				(width 0.1)
				(type default)
			)
			(layer "F.Fab")
		)
		(fp_line
			(start -0.67945 0.3048)
			(end -0.67945 -0.305054)
			(stroke
				(width 0.1)
				(type default)
			)
			(layer "F.Fab")
		)
		(fp_line
			(start -0.12065 -0.305054)
			(end -0.12065 -0.2794)
			(stroke
				(width 0.1)
				(type default)
			)
			(layer "F.Fab")
		)
		(fp_line
			(start -0.12065 -0.2794)
			(end 0.12065 -0.2794)
			(stroke
				(width 0.1)
				(type default)
			)
			(layer "F.Fab")
		)
		(fp_line
			(start -0.12065 0.2794)
			(end -0.12065 0.3048)
			(stroke
				(width 0.1)
				(type default)
			)
			(layer "F.Fab")
		)
		(fp_line
			(start -0.12065 0.3048)
			(end -0.67945 0.3048)
			(stroke
				(width 0.1)
				(type default)
			)
			(layer "F.Fab")
		)
		(fp_line
			(start 0.120396 0.2794)
			(end -0.12065 0.2794)
			(stroke
				(width 0.1)
				(type default)
			)
			(layer "F.Fab")
		)
		(fp_line
			(start 0.120396 0.3048)
			(end 0.120396 0.2794)
			(stroke
				(width 0.1)
				(type default)
			)
			(layer "F.Fab")
		)
		(fp_line
			(start 0.12065 -0.3048)
			(end 0.67945 -0.3048)
			(stroke
				(width 0.1)
				(type default)
			)
			(layer "F.Fab")
		)
		(fp_line
			(start 0.12065 -0.2794)
			(end 0.12065 -0.3048)
			(stroke
				(width 0.1)
				(type default)
			)
			(layer "F.Fab")
		)
		(fp_line
			(start 0.67945 -0.3048)
			(end 0.67945 0.3048)
			(stroke
				(width 0.1)
				(type default)
			)
			(layer "F.Fab")
		)
		(fp_line
			(start 0.67945 0.3048)
			(end 0.120396 0.3048)
			(stroke
				(width 0.1)
				(type default)
			)
			(layer "F.Fab")
		)
		(pad "1" smd circle
			(at -0.40005 0)
			(size 0 0)
			(layers "F.Cu" "F.Mask" "F.Paste")
			(net "U271_1_ADD2")
		)
		(pad "2" smd circle
			(at 0.40005 0)
			(size 0 0)
			(layers "F.Cu" "F.Mask" "F.Paste")
			(net "GND")
		)
	)
)
